# S9S_MB_2U (Grand Teton) — schematic parts with pin connectivity, parts 5880–5880 of 6093; source: Cadence DE-HDL packaged netlist (pstxprt.dat, pstxnet.dat, pstchip.dat)

U2  SOCKET4677_AZIF0045P001C01CS  SOCKET4677_AZIF0045-P001C01CS IO  pkg SOCKET4677_82X64-5XA_H466  page 13  (pins 979-1304 of 4677)
  BB65  UPI2_AC_COUPLING  IN  = PU_CPU0_UPI2_AC_COUPLING
  BB67  RSVD36  BI  = TP_SPI_IBL_CPU0_TPM_OE_N
  BB69  VSS409  POWER  = GND
  BB71  VSS410  POWER  = GND
  BB73  UPI2_RX_DP12  IN  = UPI_CPU1_CPU0_P2P2_DN<11>
  BB75  UPI2_RX_DN15  IN  = UPI_CPU1_CPU0_P2P2_DP<8>
  BB77  VSS411  POWER  = GND
  BB79  VSS412  POWER  = GND
  BB81  UPI2_TX_DP17  OUT  = UPI_CPU0_CPU1_P2P2_DP<6>
  BB83  VSS414  POWER  = GND
  BB85  PE4_TX_DP15  OUT  = P5E_CPU0_PE4_TX_DP<15>
  BB87  VSS415  POWER  = GND
  BB89  PE4_RX_DN15  IN  = P5E_CPU0_PE4_RX_DN<15>
  BB91  VSS416  POWER  = GND
  BC1  VSS417  POWER  = GND
  BC3  UPI0_TX_DP17  OUT  = UPI_CPU0_CPU1_P0P1_DP<17>
  BC5  VSS420  POWER  = GND
  BC7  UPI0_RX_DP16  IN  = UPI_CPU1_CPU0_P1P0_DN<16>
  BC9  VSS429  POWER  = GND
  BC11  PE1_RX_DN15  IN  = P5E_CPU0_PE1_RX_DN<15>
  BC13  VSS418  POWER  = GND
  BC15  PE0_TX_DP15  OUT  = P5E_CPU0_PE0_TX_DP<15>
  BC17  VSS419  POWER  = GND
  BC19  DMI_RX_DP0  IN  = DMI_CPU0_PCH_RX_C_DP<0>
  BC21  VCC_3P3_AUX0  POWER  = P3V3_AUX
  BC23  RSVD37  BI  = TP_CPU0_IFST_DONE_LVC1_R
  BC25  RSVD38  BI  = TP_I3C_MNG2_BMC_SW_SDA
  BC60  VCCINFAON35  POWER  = PVCCINFAON_CPU0
  BC62  VSS421  POWER  = GND
  BC64  RSVD39  BI  = TP_SPI_S3M_CPU0_CLK_LVC1_R
  BC66  VSS422  POWER  = GND
  BC68  PTI_DIE015  OUT  = TP_TRC_CPU0_PTI<21>
  BC70  PTI_DIE010  OUT  = TP_TRC_CPU0_PTI<16>
  BC72  VSS423  POWER  = GND
  BC74  UPI2_RX_DP23  IN  = UPI_CPU1_CPU0_P2P2_DN<0>
  BC76  VSS424  POWER  = GND
  BC78  VSS425  POWER  = GND
  BC80  UPI2_TX_DP20  OUT  = UPI_CPU0_CPU1_P2P2_DP<3>
  BC82  UPI2_TX_DN18  OUT  = UPI_CPU0_CPU1_P2P2_DN<5>
  BC84  VSS426  POWER  = GND
  BC86  VSS427  POWER  = GND
  BC88  VSS428  POWER  = GND
  BC90  VSS_VCCIN_SENSE  POWER  = VSENSE_PVCCIN_CPU0_DN
  BD2  UPI0_TX_DN17  OUT  = UPI_CPU0_CPU1_P0P1_DN<17>
  BD4  VSS433  POWER  = GND
  BD6  UPI0_RX_DP17  IN  = UPI_CPU1_CPU0_P1P0_DN<17>
  BD8  VSS434  POWER  = GND
  BD10  PE1_RX_DP15  IN  = P5E_CPU0_PE1_RX_DP<15>
  BD12  VSS430  POWER  = GND
  BD14  PE1_TX_DP15  OUT  = P5E_CPU0_PE1_TX_DP<15>
  BD16  VSS431  POWER  = GND
  BD18  DMI_RX_DP1  IN  = DMI_CPU0_PCH_RX_C_DN<1>
  BD20  VSS432  POWER  = GND
  BD22  ERROR_N2  OUT  = H_CPU0_ERR2_LVC1_R_N
  BD24  PMAX_TRIGGER_IO  BI  = H_PMAX_TRIGGER_IO_CPU0
  BD26  SVIDDATA0  BI  = SVID_DIO0_CPU0
  BD61  RSVD40  BI  = TP_SPI_S3M_CPU0_IO3_LVC1_R
  BD63  RSVD41  BI  = TP_ESPI_IBL_CPU0_ALERT1_N
  BD65  RSVD42  BI  = TP_SPI_S3M_CPU0_IO2_LVC1_R
  BD67  PTI_DIE017  OUT  = TP_TRC_CPU0_PTI<23>
  BD69  PTI_DIE012  OUT  = TP_TRC_CPU0_PTI<18>
  BD71  RSVD43  BI  = NC_CPU0_MDFI_DIE01_NS1
  BD73  UPI2_RX_DN23  IN  = UPI_CPU1_CPU0_P2P2_DP<0>
  BD75  UPI2_RX_DP15  IN  = UPI_CPU1_CPU0_P2P2_DN<8>
  BD77  RSVD44  BI  = TP_CPU0_SPARE13
  BD79  UPI2_TX_DN20  OUT  = UPI_CPU0_CPU1_P2P2_DN<3>
  BD81  VSS435  POWER  = GND
  BD83  UPI2_TX_DP19  OUT  = UPI_CPU0_CPU1_P2P2_DP<4>
  BD85  VSS437  POWER  = GND
  BD87  VCCIN_SENSE  POWER  = VSENSE_PVCCIN_CPU0_DP
  BD89  VSS439  POWER  = GND
  BD91  VCCIN0  POWER  = PVCCIN_CPU0
  BE1  UPI0_TX_DP18  OUT  = UPI_CPU0_CPU1_P0P1_DP<18>
  BE3  VCCD_HV13  POWER  = PVCCD_HV_CPU0
  BE5  UPI0_RX_DN17  IN  = UPI_CPU1_CPU0_P1P0_DP<17>
  BE7  VCCD_HV14  POWER  = PVCCD_HV_CPU0
  BE9  PE1_RX_DP14  IN  = P5E_CPU0_PE1_RX_DP<14>
  BE11  VCCD_HV12  POWER  = PVCCD_HV_CPU0
  BE13  PE1_TX_DN15  OUT  = P5E_CPU0_PE1_TX_DN<15>
  BE15  VCCINFAON36  POWER  = PVCCINFAON_CPU0
  BE17  DMI_RX_DN1  IN  = DMI_CPU0_PCH_RX_C_DP<1>
  BE19  VCCVNN1  POWER  = PVNN_MAIN_CPU0
  BE21  RSVD45  BI  = TP_CPU0_DIE_HVM_EN_LVC1
  BE23  RSVD46  BI  = TP_CPU0_IFST_KOT_LVC1_R
  BE25  RSVD47  BI  = TP_I3C_MNG2_BMC_SW_SCL
  BE60  VCCINFAON37  POWER  = PVCCINFAON_CPU0
  BE62  RSVD48  BI  = TP_ESPI_IBL_CPU0_ALERT0_LVC1_N
  BE64  VSS440  POWER  = GND
  BE66  VSS441  POWER  = GND
  BE68  VSS442  POWER  = GND
  BE70  PTI_DIE011  OUT  = TP_TRC_CPU0_PTI<17>
  BE72  VCCFA_EHV_FIVRA27  POWER  = PVCCFA_EHV_FIVRA_CPU0
  BE74  VSS443  POWER  = GND
  BE76  VSS444  POWER  = GND
  BE78  VSS445  POWER  = GND
  BE80  UPI2_TX_DP22  OUT  = UPI_CPU0_CPU1_P2P2_DP<1>
  BE82  UPI2_TX_DN19  OUT  = UPI_CPU0_CPU1_P2P2_DN<4>
  BE84  VSS446  POWER  = GND
  BE86  VCCIN1  POWER  = PVCCIN_CPU0
  BE88  VCCIN2  POWER  = PVCCIN_CPU0
  BE90  VCCIN3  POWER  = PVCCIN_CPU0
  BF2  UPI0_TX_DN18  OUT  = UPI_CPU0_CPU1_P0P1_DN<18>
  BF4  VSS450  POWER  = GND
  BF6  UPI0_RX_DN18  IN  = UPI_CPU1_CPU0_P1P0_DP<18>
  BF8  VSS456  POWER  = GND
  BF10  PE1_RX_DN14  IN  = P5E_CPU0_PE1_RX_DN<14>
  BF12  VSS447  POWER  = GND
  BF14  PE1_TX_DN14  OUT  = P5E_CPU0_PE1_TX_DN<14>
  BF16  VSS448  POWER  = GND
  BF18  DMI_RX_DN2  IN  = DMI_CPU0_PCH_RX_C_DN<2>
  BF20  VSS449  POWER  = GND
  BF22  ERROR_N0  OUT  = H_CPU0_ERR0_LVC1_R_N
  BF24  RSVD49  BI  = TP_CPU0_IFST_TRIG_LVC1_R
  BF26  SVIDCLK1  OUT  = SVID_CLK1_CPU0
  BF61  VSS451  POWER  = GND
  BF63  VSS452  POWER  = GND
  BF65  RSVD50  BI  = TP_ESPI_IBL_CPU0_CS0_LVC1_N
  BF67  PTI_DIE01_STB_0  OUT  = TP_TRC_CPU0_PTI2_CLK
  BF69  PTI_DIE013  OUT  = TP_TRC_CPU0_PTI<19>
  BF71  RSVD51  BI  = NC_CPU0_MDFI_DIE01_NS0
  BF73  VSS453  POWER  = GND
  BF75  VSS454  POWER  = GND
  BF77  VCCFA_EHV_FIVRA28  POWER  = PVCCFA_EHV_FIVRA_CPU0
  BF79  VSS455  POWER  = GND
  BF81  UPI2_TX_DN21  OUT  = UPI_CPU0_CPU1_P2P2_DN<2>
  BF83  VSS457  POWER  = GND
  BF85  VCCIN4  POWER  = PVCCIN_CPU0
  BF87  VCCIN5  POWER  = PVCCIN_CPU0
  BF89  VCCIN6  POWER  = PVCCIN_CPU0
  BF91  VCCIN7  POWER  = PVCCIN_CPU0
  BG1  VSS458  POWER  = GND
  BG3  UPI0_TX_DP19  OUT  = UPI_CPU0_CPU1_P0P1_DP<19>
  BG5  VSS464  POWER  = GND
  BG7  UPI0_RX_DP18  IN  = UPI_CPU1_CPU0_P1P0_DN<18>
  BG9  VSS466  POWER  = GND
  BG11  PE1_RX_DN13  IN  = P5E_CPU0_PE1_RX_DN<13>
  BG13  VSS459  POWER  = GND
  BG15  PE1_TX_DP14  OUT  = P5E_CPU0_PE1_TX_DP<14>
  BG17  VSS460  POWER  = GND
  BG19  DMI_RX_DP2  IN  = DMI_CPU0_PCH_RX_C_DP<2>
  BG21  VSS461  POWER  = GND
  BG23  VSS462  POWER  = GND
  BG25  VSS463  POWER  = GND
  BG60  VCCINFAON38  POWER  = PVCCINFAON_CPU0
  BG62  RSVD52  BI  = TP_CLK_66M_ESPI_IBL_CPU0_LVC1
  BG64  RSVD53  BI  = TP_RST_ESPI_IBL_CPU0_LVC1_N
  BG66  PTI_DIE0111  OUT  = TP_TRC_CPU0_PTI<27>
  BG68  PTI_DIE016  OUT  = TP_TRC_CPU0_PTI<22>
  BG70  VSS465  POWER  = GND
  BG72  PROC_ID0  IN  = FM_CPU0_PROC_ID0
  BG74  UPI2_RX_DN20  IN  = UPI_CPU1_CPU0_P2P2_DP<3>
  BG76  UPI2_RX_DP17  IN  = UPI_CPU1_CPU0_P2P2_DP<6>
  BG78  RSVD54  BI  = NC_CPU0_HBM3_VIEWDIG0
  BG80  UPI2_TX_DN22  OUT  = UPI_CPU0_CPU1_P2P2_DN<1>
  BG82  UPI2_TX_DP21  OUT  = UPI_CPU0_CPU1_P2P2_DP<2>
  BG84  VCCIN8  POWER  = PVCCIN_CPU0
  BG86  VCCIN9  POWER  = PVCCIN_CPU0
  BG88  VCCIN10  POWER  = PVCCIN_CPU0
  BG90  VCCIN11  POWER  = PVCCIN_CPU0
  BH2  UPI0_TX_DN19  OUT  = UPI_CPU0_CPU1_P0P1_DN<19>
  BH4  VSS470  POWER  = GND
  BH6  UPI0_RX_DP19  IN  = UPI_CPU1_CPU0_P1P0_DN<19>
  BH8  VSS475  POWER  = GND
  BH10  PE1_RX_DP13  IN  = P5E_CPU0_PE1_RX_DP<13>
  BH12  VSS467  POWER  = GND
  BH14  PE1_TX_DP13  OUT  = P5E_CPU0_PE1_TX_DP<13>
  BH16  VSS468  POWER  = GND
  BH18  DMI_RX_DP3  IN  = DMI_CPU0_PCH_RX_C_DN<3>
  BH20  VSS469  POWER  = GND
  BH22  RMCA_N  BI  = H_CPU0_RMCA_LVC1_R_N
  BH24  PECI  BI  = PECI_CPU0_GTL_R
  BH26  SVIDCLK0  OUT  = SVID_CLK0_CPU0
  BH61  RESET_N  IN  = RST_CPU0_LVC1_N
  BH63  RSVD55  BI  = TP_ESPI_IBL_CPU0_OE_LVC1_N
  BH65  RSVD56  BI  = TP_ESPI_IBL_CPU0_CS1_N
  BH67  VSS472  POWER  = GND
  BH69  PTI_DIE014  OUT  = TP_TRC_CPU0_PTI<20>
  BH71  PROC_ID1  IN  = FM_CPU0_PROC_ID1
  BH73  VSS473  POWER  = GND
  BH75  UPI2_RX_DN17  IN  = UPI_CPU1_CPU0_P2P2_DN<6>
  BH77  VSS474  POWER  = GND
  BH79  VCCFA_EHV_FIVRA29  POWER  = PVCCFA_EHV_FIVRA_CPU0
  BH81  VSS476  POWER  = GND
  BH83  VSS477  POWER  = GND
  BH85  VCCIN12  POWER  = PVCCIN_CPU0
  BH87  VCCIN13  POWER  = PVCCIN_CPU0
  BH89  VCCIN14  POWER  = PVCCIN_CPU0
  BH91  VCCIN15  POWER  = PVCCIN_CPU0
  BJ1  UPI0_TX_DP20  OUT  = UPI_CPU0_CPU1_P0P1_DN<20>
  BJ3  VCCD_HV16  POWER  = PVCCD_HV_CPU0
  BJ5  UPI0_RX_DN19  IN  = UPI_CPU1_CPU0_P1P0_DP<19>
  BJ7  VCCD_HV17  POWER  = PVCCD_HV_CPU0
  BJ9  PE1_RX_DP12  IN  = P5E_CPU0_PE1_RX_DP<12>
  BJ11  VCCD_HV15  POWER  = PVCCD_HV_CPU0
  BJ13  PE1_TX_DN13  OUT  = P5E_CPU0_PE1_TX_DN<13>
  BJ15  VCCINFAON39  POWER  = PVCCINFAON_CPU0
  BJ17  DMI_RX_DN3  IN  = DMI_CPU0_PCH_RX_C_DP<3>
  BJ19  VCCVNN2  POWER  = PVNN_MAIN_CPU0
  BJ21  RSVD57  BI  = NC_CPU0_MDFI_DIE00_NS1
  BJ23  MBP2_N  BI  = DBP_CPU0_HOOK8_MBP2_GTL_QS_R_N
  BJ25  SVIDALERT1_N  IN  = SVID_ALERT1_CPU0_N
  BJ60  VCCINFAON40  POWER  = PVCCINFAON_CPU0
  BJ62  VSS479  POWER  = GND
  BJ64  RSVD58  BI  = TP_ESPI_IBL_CPU0_IO1_LVC1
  BJ66  PTI_DIE0112  OUT  = TP_TRC_CPU0_PTI<28>
  BJ68  VSS480  POWER  = GND
  BJ70  RSVD59  BI  = NC_CPU0_VIEWPIN_DIE01<3>
  BJ72  VCCFA_EHV_FIVRA30  POWER  = PVCCFA_EHV_FIVRA_CPU0
  BJ74  UPI2_RX_DP20  IN  = UPI_CPU1_CPU0_P2P2_DN<3>
  BJ76  UPI2_RX_DN18  IN  = UPI_CPU1_CPU0_P2P2_DN<5>
  BJ78  VCCFA_EHV_FIVRA31  POWER  = PVCCFA_EHV_FIVRA_CPU0
  BJ80  VSS481  POWER  = GND
  BJ82  VSS482  POWER  = GND
  BJ84  VSS483  POWER  = GND
  BJ86  VSS484  POWER  = GND
  BJ88  VSS485  POWER  = GND
  BJ90  VSS486  POWER  = GND
  BK2  UPI0_TX_DN20  OUT  = UPI_CPU0_CPU1_P0P1_DP<20>
  BK4  VSS490  POWER  = GND
  BK6  UPI0_RX_DN20  IN  = UPI_CPU1_CPU0_P1P0_DP<20>
  BK8  VSS496  POWER  = GND
  BK10  PE1_RX_DN12  IN  = P5E_CPU0_PE1_RX_DN<12>
  BK12  VSS487  POWER  = GND
  BK14  PE1_TX_DN12  OUT  = P5E_CPU0_PE1_TX_DN<12>
  BK16  VSS488  POWER  = GND
  BK18  DMI_RX_DN4  IN  = DMI_CPU0_PCH_RX_C_DP<4>
  BK20  VSS489  POWER  = GND
  BK22  RSVD60  BI  = NC_CPU0_MDFI_DIE00_NS0
  BK24  MBP3_N  BI  = DBP_CPU0_HOOK9_MBP3_GTL_QS_R_N
  BK26  SVIDALERT0_N  IN  = SVID_ALERT0_CPU0_N
  BK61  VCCINFAON41  POWER  = PVCCINFAON_CPU0
  BK63  RSVD61  BI  = TP_ESPI_IBL_CPU0_IO0_LVC1
  BK65  VSS491  POWER  = GND
  BK67  PTI_DIE01_STB_1  OUT  = TP_TRC_CPU0_PTI3_CLK
  BK69  PTI_DIE018  OUT  = TP_TRC_CPU0_PTI<24>
  BK71  VSS492  POWER  = GND
  BK73  UPI2_RX_DN22  IN  = UPI_CPU1_CPU0_P2P2_DN<1>
  BK75  VSS494  POWER  = GND
  BK77  UPI2_RX_DP18  IN  = UPI_CPU1_CPU0_P2P2_DP<5>
  BK79  VSS495  POWER  = GND
  BK81  VCCIN16  POWER  = PVCCIN_CPU0
  BK83  VCCIN17  POWER  = PVCCIN_CPU0
  BK85  VCCIN18  POWER  = PVCCIN_CPU0
  BK87  VCCIN19  POWER  = PVCCIN_CPU0
  BK89  VCCIN20  POWER  = PVCCIN_CPU0
  BK91  VCCIN21  POWER  = PVCCIN_CPU0
  BL1  VSS497  POWER  = GND
  BL3  UPI0_TX_DP21  OUT  = UPI_CPU0_CPU1_P0P1_DN<21>
  BL5  VSS500  POWER  = GND
  BL7  UPI0_RX_DP20  IN  = UPI_CPU1_CPU0_P1P0_DN<20>
  BL9  VSS505  POWER  = GND
  BL11  PE1_RX_DN11  IN  = P5E_CPU0_PE1_RX_DN<11>
  BL13  VSS498  POWER  = GND
  BL15  PE1_TX_DP12  OUT  = P5E_CPU0_PE1_TX_DP<12>
  BL17  VSS499  POWER  = GND
  BL19  DMI_RX_DP4  IN  = DMI_CPU0_PCH_RX_C_DN<4>
  BL21  RSVD62  BI  = NC_CPU0_PE0_APROBE<1>
  BL23  MBP0_N  BI  = DBP_CPU0_MBP0_GTL_R_N
  BL25  SVIDDATA1  BI  = SVID_DIO1_CPU0
  BL60  RSVD63  BI  = NC_CPU0_HBM3_VIEWDIG1
  BL62  THERMTRIP_N  OUT  = H_CPU0_THERMTRIP_LVC1_R_N
  BL64  PKG_ID0  IN  = FM_CPU0_PKGID0
  BL66  PTI_DIE0113  OUT  = TP_TRC_CPU0_PTI<29>
  BL68  VSS501  POWER  = GND
  BL70  VSS502  POWER  = GND
  BL72  VSS503  POWER  = GND
  BL74  UPI2_RX_DP22  IN  = UPI_CPU1_CPU0_P2P2_DP<1>
  BL76  UPI2_RX_DN19  IN  = UPI_CPU1_CPU0_P2P2_DP<4>
  BL78  VSS504  POWER  = GND
  BL80  VCCIN22  POWER  = PVCCIN_CPU0
  BL82  VCCIN23  POWER  = PVCCIN_CPU0
  BL84  VCCIN24  POWER  = PVCCIN_CPU0
  BL86  VCCIN25  POWER  = PVCCIN_CPU0
  BL88  VCCIN26  POWER  = PVCCIN_CPU0
  BL90  VCCIN27  POWER  = PVCCIN_CPU0
  BM2  UPI0_TX_DN21  OUT  = UPI_CPU0_CPU1_P0P1_DP<21>
  BM4  VSS512  POWER  = GND
  BM6  UPI0_RX_DP21  IN  = UPI_CPU1_CPU0_P1P0_DN<21>
  BM8  VSS517  POWER  = GND
  BM10  PE1_RX_DP11  IN  = P5E_CPU0_PE1_RX_DP<11>
  BM12  VSS506  POWER  = GND
  BM14  PE1_TX_DP11  OUT  = P5E_CPU0_PE1_TX_DP<11>
  BM16  VSS507  POWER  = GND
  BM18  DMI_RX_DP5  IN  = DMI_CPU0_PCH_RX_C_DN<5>
  BM20  VSS508  POWER  = GND
  BM22  VSS509  POWER  = GND
  BM24  VSS510  POWER  = GND
  BM26  VSS511  POWER  = GND
  BM61  VSS513  POWER  = GND
  BM63  RSVD64  BI  = TP_ESPI_IBL_CPU0_IO3_LVC1
  BM65  RSVD65  BI  = NC_CPU0_SOC_SPARE1
  BM67  PTI_DIE0114  OUT  = TP_TRC_CPU0_PTI<30>
  BM69  PTI_DIE019  OUT  = TP_TRC_CPU0_PTI<25>
  BM71  UPI2_TX_DN23  OUT  = UPI_CPU0_CPU1_P2P2_DN<0>
  BM73  VSS515  POWER  = GND
  BM75  UPI2_RX_DP21  IN  = UPI_CPU1_CPU0_P2P2_DN<2>
  BM77  VSS516  POWER  = GND
  BM79  VCCIN28  POWER  = PVCCIN_CPU0
  BM81  VCCIN29  POWER  = PVCCIN_CPU0
  BM83  VCCIN30  POWER  = PVCCIN_CPU0
  BM85  VCCIN31  POWER  = PVCCIN_CPU0
  BM87  VCCIN32  POWER  = PVCCIN_CPU0
  BM89  VCCIN33  POWER  = PVCCIN_CPU0
  BM91  VCCIN34  POWER  = PVCCIN_CPU0
  BN3  UPI0_TX_DP22  OUT  = UPI_CPU0_CPU1_P0P1_DN<22>
  BN5  UPI0_RX_DN21  IN  = UPI_CPU1_CPU0_P1P0_DP<21>
  BN7  VCCD_HV18  POWER  = PVCCD_HV_CPU0
  BN9  PE1_RX_DP10  IN  = P5E_CPU0_PE1_RX_DP<10>
  BN11  VSS_VCCD_HV_SENSE  POWER  = VSENSE_PVCCD_HV_CPU0_DN
  BN13  PE1_TX_DN11  OUT  = P5E_CPU0_PE1_TX_DN<11>
  BN15  VCCINFAON42  POWER  = PVCCINFAON_CPU0
  BN17  DMI_RX_DN5  IN  = DMI_CPU0_PCH_RX_C_DP<5>
  BN19  VCCVNN3  POWER  = PVNN_MAIN_CPU0
  BN21  RSVD66  BI  = NC_CPU0_PE0_APROBE<0>
  BN23  BMCINIT  IN  = H_CPU0_BMCINIT_LVC1
  BN25  MBP1_N  BI  = DBP_CPU0_MBP1_GTL_R_N
  BN27  PTI_DIE0012  OUT  = TP_TRC_CPU0_PTI<12>
  BN29  PTI_DIE0014  OUT  = TP_TRC_CPU0_PTI<14>
  BN31  VSS518  POWER  = GND
  BN33  VCCIN35  POWER  = PVCCIN_CPU0
  BN35  VCCIN36  POWER  = PVCCIN_CPU0
  BN37  VCCIN37  POWER  = PVCCIN_CPU0
  BN39  VCCIN38  POWER  = PVCCIN_CPU0
  BN41  VCCIN39  POWER  = PVCCIN_CPU0
  BN43  VCCIN40  POWER  = PVCCIN_CPU0
  BN45  VCCIN41  POWER  = PVCCIN_CPU0
